(kicad_pcb
	(version 20260206)
	(generator "pcbnew")
	(generator_version "10.0")
	(general
		(thickness 1.6)
		(legacy_teardrops no)
	)
	(paper "A4")
	(title_block
		(title "Bryce Canyon_R.DPB_16317-1_OCP.brd")
		(comment 1 "Bryce Canyon / footprints 468-474 of 2099")
	)
	(layers
		(0 "F.Cu" signal "TOP")
		(4 "In1.Cu" signal "L2GND")
		(6 "In2.Cu" signal "L3")
		(8 "In3.Cu" signal "L4VCC")
		(10 "In4.Cu" signal "L5VCC")
		(12 "In5.Cu" signal "L6")
		(14 "In6.Cu" signal "L7GND")
		(2 "B.Cu" signal "BOTTOM")
		(9 "F.Adhes" user "F.Adhesive")
		(11 "B.Adhes" user "B.Adhesive")
		(13 "F.Paste" user "Package Geometry/Pastemask Top")
		(15 "B.Paste" user "Package Geometry/Pastemask Bottom")
		(5 "F.SilkS" user "Ref Des/Silkscreen Top")
		(7 "B.SilkS" user "Ref Des/Silkscreen Bottom")
		(1 "F.Mask" user "Board Geometry/Soldermask Top")
		(3 "B.Mask" user "Board Geometry/Soldermask Bottom")
		(17 "Dwgs.User" user "User.Drawings")
		(19 "Cmts.User" user "User.Comments")
		(21 "Eco1.User" user "User.Eco1")
		(23 "Eco2.User" user "User.Eco2")
		(25 "Edge.Cuts" user "Board Geometry/Outline")
		(27 "Margin" user)
		(31 "F.CrtYd" user "Package Geometry/Place Bound Top")
		(29 "B.CrtYd" user "Package Geometry/Place Bound Bottom")
		(35 "F.Fab" user "Ref Des/Assembly Top")
		(33 "B.Fab" user "Ref Des/Assembly Bottom")
	)
	(footprint ""
		(layer "F.Cu")
		(at 224.550224 -329.060556)
		(property "Reference" "C510"
			(at 0 0 0)
			(layer "F.SilkS")
			(hide yes)
			(effects
				(font
					(size 1.27 1.27)
				)
			)
		)
		(property "Value" "SC22U25V6KX-2-GP-U"
			(at -2.860802 -5.279644 0)
			(unlocked yes)
			(layer "F.Fab")
			(hide yes)
			(effects
				(font
					(size 1.016 1.016)
					(thickness 0.1524)
				)
			)
		)
		(property "Device Type" "C1206-TO0D3H75"
			(at -2.860802 -6.803644 0)
			(unlocked yes)
			(layer "F.Fab")
			(hide yes)
			(effects
				(font
					(size 1.016 1.016)
					(thickness 0.1524)
				)
			)
		)
		(duplicate_pad_numbers_are_jumpers no)
		(fp_line
			(start -1.3081 -2.3749)
			(end 1.3081 -2.3749)
			(stroke
				(width 0.1524)
				(type default)
			)
			(layer "F.SilkS")
		)
		(fp_line
			(start -1.3081 2.3749)
			(end -1.3081 -2.3749)
			(stroke
				(width 0.1524)
				(type default)
			)
			(layer "F.SilkS")
		)
		(fp_line
			(start 1.3081 -2.3749)
			(end 1.3081 2.3749)
			(stroke
				(width 0.1524)
				(type default)
			)
			(layer "F.SilkS")
		)
		(fp_line
			(start 1.3081 2.3749)
			(end -1.3081 2.3749)
			(stroke
				(width 0.1524)
				(type default)
			)
			(layer "F.SilkS")
		)
		(fp_rect
			(start -0.8001 1.6002)
			(end 0.8001 -1.6002)
			(stroke
				(width 0)
				(type default)
			)
			(fill no)
			(layer "F.CrtYd")
		)
		(fp_poly
			(pts
				(xy -1.5621 2.4511) (xy -1.5621 1.6002) (xy 0.8001 1.6002) (xy 0.8001 -1.6002) (xy -0.8001 -1.6002)
				(xy -0.8001 1.5875) (xy -1.5621 1.5875) (xy -1.5621 -2.4511) (xy 1.5621 -2.4511) (xy 1.5621 2.4511)
			)
			(stroke
				(width 0)
				(type default)
			)
			(fill no)
			(layer "F.CrtYd")
		)
		(fp_rect
			(start -1.5621 2.4511)
			(end 1.5621 -2.4511)
			(stroke
				(width 0)
				(type default)
			)
			(fill no)
			(layer "F.Fab")
		)
		(pad "1" smd rect
			(at 0 -1.392936)
			(size 2.1082 1.4478)
			(layers "F.Cu" "F.Mask" "F.Paste")
			(net "P12V_IN")
		)
		(pad "2" smd rect
			(at 0 1.392936)
			(size 2.1082 1.4478)
			(layers "F.Cu" "F.Mask" "F.Paste")
			(net "GND")
		)
	)
	(footprint ""
		(layer "F.Cu")
		(at 363.601 -128.651)
		(property "Reference" "R519"
			(at 0 0 0)
			(layer "F.SilkS")
			(hide yes)
			(effects
				(font
					(size 1.27 1.27)
				)
			)
		)
		(property "Value" "4K7R2F-GP"
			(at 0.064008 -3.993896 0)
			(unlocked yes)
			(layer "F.Fab")
			(hide yes)
			(effects
				(font
					(size 1.016 1.016)
					(thickness 0.1524)
				)
			)
		)
		(property "Device Type" "R402H16"
			(at 0.064008 -5.517896 0)
			(unlocked yes)
			(layer "F.Fab")
			(hide yes)
			(effects
				(font
					(size 1.016 1.016)
					(thickness 0.1524)
				)
			)
		)
		(duplicate_pad_numbers_are_jumpers no)
		(fp_line
			(start -0.508 -0.9398)
			(end -0.508 0.9398)
			(stroke
				(width 0.1524)
				(type default)
			)
			(layer "F.SilkS")
		)
		(fp_line
			(start 0.508 -0.9398)
			(end -0.508 -0.9398)
			(stroke
				(width 0.1524)
				(type default)
			)
			(layer "F.SilkS")
		)
		(fp_rect
			(start -0.508 0.9398)
			(end 0.508 -0.9398)
			(stroke
				(width 0)
				(type default)
			)
			(fill no)
			(layer "F.CrtYd")
		)
		(fp_rect
			(start -0.508 0.9398)
			(end 0.508 -0.9398)
			(stroke
				(width 0)
				(type default)
			)
			(fill no)
			(layer "F.Fab")
		)
		(pad "1" smd custom
			(at 0 -0.4445)
			(size 0.1397 0.1397)
			(layers "F.Cu" "F.Mask" "F.Paste")
			(net "SW_PWR_R_HDD19")
			(options
				(clearance outline)
				(anchor circle)
			)
			(primitives
				(gr_poly
					(pts
						(arc
							(start -0.1778 -0.2794)
							(mid -0.249642 -0.249642)
							(end -0.2794 -0.1778)
						)
						(arc
							(start -0.2794 0.1778)
							(mid -0.249642 0.249642)
							(end -0.1778 0.2794)
						)
						(arc
							(start 0.1778 0.2794)
							(mid 0.249642 0.249642)
							(end 0.2794 0.1778)
						)
						(arc
							(start 0.2794 -0.1778)
							(mid 0.249642 -0.249642)
							(end 0.1778 -0.2794)
						)
					)
					(width 0)
					(fill yes)
				)
			)
		)
		(pad "2" smd custom
			(at 0 0.4445)
			(size 0.1397 0.1397)
			(layers "F.Cu" "F.Mask" "F.Paste")
			(net "GND")
			(options
				(clearance outline)
				(anchor circle)
			)
			(primitives
				(gr_poly
					(pts
						(arc
							(start -0.1778 -0.2794)
							(mid -0.249642 -0.249642)
							(end -0.2794 -0.1778)
						)
						(arc
							(start -0.2794 0.1778)
							(mid -0.249642 0.249642)
							(end -0.1778 0.2794)
						)
						(arc
							(start 0.1778 0.2794)
							(mid 0.249642 0.249642)
							(end 0.2794 0.1778)
						)
						(arc
							(start 0.2794 -0.1778)
							(mid 0.249642 -0.249642)
							(end 0.1778 -0.2794)
						)
					)
					(width 0)
					(fill yes)
				)
			)
		)
	)
	(footprint ""
		(layer "F.Cu")
		(at 52.07 -249.555 180)
		(property "Reference" "Q3"
			(at 0 0 180)
			(layer "F.SilkS")
			(hide yes)
			(effects
				(font
					(size 1.27 1.27)
				)
			)
		)
		(property "Value" "2N7002KDW-GP"
			(at -2.3622 -8.2042 180)
			(unlocked yes)
			(layer "F.Fab")
			(hide yes)
			(effects
				(font
					(size 1.016 1.016)
					(thickness 0.1524)
				)
			)
		)
		(property "Device Type" "SOT-363H44"
			(at -2.3622 -10.1092 180)
			(unlocked yes)
			(layer "F.Fab")
			(hide yes)
			(effects
				(font
					(size 1.016 1.016)
					(thickness 0.1524)
				)
			)
		)
		(duplicate_pad_numbers_are_jumpers no)
		(fp_line
			(start 1.4478 1.7018)
			(end 1.4478 -1.7018)
			(stroke
				(width 0.1524)
				(type default)
			)
			(layer "F.SilkS")
		)
		(fp_line
			(start 1.4478 -1.7018)
			(end -1.4478 -1.7018)
			(stroke
				(width 0.1524)
				(type default)
			)
			(layer "F.SilkS")
		)
		(fp_line
			(start -1.27 1.524)
			(end -1.27 0.6604)
			(stroke
				(width 0.4826)
				(type default)
			)
			(layer "F.SilkS")
		)
		(fp_line
			(start -1.4478 1.7018)
			(end 1.4478 1.7018)
			(stroke
				(width 0.1524)
				(type default)
			)
			(layer "F.SilkS")
		)
		(fp_line
			(start -1.4478 -1.7018)
			(end -1.4478 1.7018)
			(stroke
				(width 0.1524)
				(type default)
			)
			(layer "F.SilkS")
		)
		(fp_poly
			(pts
				(xy -1.524 -1.778) (xy 1.524 -1.778) (xy 1.524 1.778) (xy -1.524 1.778)
			)
			(stroke
				(width 0)
				(type default)
			)
			(fill no)
			(layer "F.CrtYd")
		)
		(fp_poly
			(pts
				(xy -1.524 -1.778) (xy 1.524 -1.778) (xy 1.524 1.778) (xy -1.524 1.778)
			)
			(stroke
				(width 0)
				(type default)
			)
			(fill no)
			(layer "F.Fab")
		)
		(pad "1" smd rect
			(at -0.65024 0.9398 180)
			(size 0.4064 1.016)
			(layers "F.Cu" "F.Mask" "F.Paste")
			(net "GND")
		)
		(pad "2" smd rect
			(at 0 0.9398 180)
			(size 0.4064 1.016)
			(layers "F.Cu" "F.Mask" "F.Paste")
			(net "SW_PWR_R_HDD1")
		)
		(pad "3" smd rect
			(at 0.65024 0.9398 180)
			(size 0.4064 1.016)
			(layers "F.Cu" "F.Mask" "F.Paste")
			(net "SW_HDD_P1")
		)
		(pad "4" smd rect
			(at 0.65024 -0.9398 180)
			(size 0.4064 1.016)
			(layers "F.Cu" "F.Mask" "F.Paste")
			(net "GND")
		)
		(pad "5" smd rect
			(at 0 -0.9398 180)
			(size 0.4064 1.016)
			(layers "F.Cu" "F.Mask" "F.Paste")
			(net "SW_HDD_G1")
		)
		(pad "6" smd rect
			(at -0.65024 -0.9398 180)
			(size 0.4064 1.016)
			(layers "F.Cu" "F.Mask" "F.Paste")
			(net "SW_HDD_R1")
		)
	)
	(footprint ""
		(layer "F.Cu")
		(at 407.1366 -33.782 90)
		(property "Reference" "C455"
			(at 0 0 90)
			(layer "F.SilkS")
			(hide yes)
			(effects
				(font
					(size 1.27 1.27)
				)
			)
		)
		(property "Value" "SCD033U25V2KX-GP"
			(at 1.1811 -2.7051 90)
			(unlocked yes)
			(layer "F.Fab")
			(hide yes)
			(effects
				(font
					(size 1.016 1.016)
					(thickness 0.1524)
				)
			)
		)
		(property "Device Type" "C402H22"
			(at 1.1811 -4.2291 90)
			(unlocked yes)
			(layer "F.Fab")
			(hide yes)
			(effects
				(font
					(size 1.016 1.016)
					(thickness 0.1524)
				)
			)
		)
		(duplicate_pad_numbers_are_jumpers no)
		(fp_rect
			(start -0.4318 0.9525)
			(end 0.4318 -0.9525)
			(stroke
				(width 0)
				(type default)
			)
			(fill no)
			(layer "F.CrtYd")
		)
		(fp_rect
			(start -0.4318 0.9525)
			(end 0.4318 -0.9525)
			(stroke
				(width 0)
				(type default)
			)
			(fill no)
			(layer "F.Fab")
		)
		(pad "1" smd custom
			(at 0 -0.4445 90)
			(size 0.1524 0.1524)
			(layers "F.Cu" "F.Mask" "F.Paste")
			(net "P12V_B")
			(options
				(clearance outline)
				(anchor circle)
			)
			(primitives
				(gr_poly
					(pts
						(arc
							(start 0.3048 -0.2032)
							(mid 0.275042 -0.275042)
							(end 0.2032 -0.3048)
						)
						(arc
							(start -0.2032 -0.3048)
							(mid -0.275042 -0.275042)
							(end -0.3048 -0.2032)
						)
						(arc
							(start -0.3048 0.2032)
							(mid -0.275042 0.275042)
							(end -0.2032 0.3048)
						)
						(arc
							(start 0.2032 0.3048)
							(mid 0.275042 0.275042)
							(end 0.3048 0.2032)
						)
					)
					(width 0)
					(fill yes)
				)
			)
		)
		(pad "2" smd custom
			(at 0 0.4445 90)
			(size 0.1524 0.1524)
			(layers "F.Cu" "F.Mask" "F.Paste")
			(net "SW_HDD_N32")
			(options
				(clearance outline)
				(anchor circle)
			)
			(primitives
				(gr_poly
					(pts
						(arc
							(start 0.3048 -0.2032)
							(mid 0.275042 -0.275042)
							(end 0.2032 -0.3048)
						)
						(arc
							(start -0.2032 -0.3048)
							(mid -0.275042 -0.275042)
							(end -0.3048 -0.2032)
						)
						(arc
							(start -0.3048 0.2032)
							(mid -0.275042 0.275042)
							(end -0.2032 0.3048)
						)
						(arc
							(start 0.2032 0.3048)
							(mid 0.275042 0.275042)
							(end 0.3048 0.2032)
						)
					)
					(width 0)
					(fill yes)
				)
			)
		)
	)
	(footprint ""
		(layer "F.Cu")
		(at 245.745 -311.912)
		(property "Reference" "R1094"
			(at 0 0 0)
			(layer "F.SilkS")
			(hide yes)
			(effects
				(font
					(size 1.27 1.27)
				)
			)
		)
		(property "Value" "0R2J-2-GP"
			(at 0.064008 -3.993896 0)
			(unlocked yes)
			(layer "F.Fab")
			(hide yes)
			(effects
				(font
					(size 1.016 1.016)
					(thickness 0.1524)
				)
			)
		)
		(property "Device Type" "R402H16"
			(at 0.064008 -5.517896 0)
			(unlocked yes)
			(layer "F.Fab")
			(hide yes)
			(effects
				(font
					(size 1.016 1.016)
					(thickness 0.1524)
				)
			)
		)
		(duplicate_pad_numbers_are_jumpers no)
		(fp_line
			(start -0.508 -0.9398)
			(end -0.508 0.9398)
			(stroke
				(width 0.1524)
				(type default)
			)
			(layer "F.SilkS")
		)
		(fp_line
			(start 0.508 -0.9398)
			(end -0.508 -0.9398)
			(stroke
				(width 0.1524)
				(type default)
			)
			(layer "F.SilkS")
		)
		(fp_rect
			(start -0.508 0.9398)
			(end 0.508 -0.9398)
			(stroke
				(width 0)
				(type default)
			)
			(fill no)
			(layer "F.CrtYd")
		)
		(fp_rect
			(start -0.508 0.9398)
			(end 0.508 -0.9398)
			(stroke
				(width 0)
				(type default)
			)
			(fill no)
			(layer "F.Fab")
		)
		(pad "1" smd custom
			(at 0 -0.4445)
			(size 0.1397 0.1397)
			(layers "F.Cu" "F.Mask" "F.Paste")
			(net "GND")
			(options
				(clearance outline)
				(anchor circle)
			)
			(primitives
				(gr_poly
					(pts
						(arc
							(start -0.1778 -0.2794)
							(mid -0.249642 -0.249642)
							(end -0.2794 -0.1778)
						)
						(arc
							(start -0.2794 0.1778)
							(mid -0.249642 0.249642)
							(end -0.1778 0.2794)
						)
						(arc
							(start 0.1778 0.2794)
							(mid 0.249642 0.249642)
							(end 0.2794 0.1778)
						)
						(arc
							(start 0.2794 -0.1778)
							(mid 0.249642 -0.249642)
							(end 0.1778 -0.2794)
						)
					)
					(width 0)
					(fill yes)
				)
			)
		)
		(pad "2" smd custom
			(at 0 0.4445)
			(size 0.1397 0.1397)
			(layers "F.Cu" "F.Mask" "F.Paste")
			(net "MAX31790_A_FREQ_ST")
			(options
				(clearance outline)
				(anchor circle)
			)
			(primitives
				(gr_poly
					(pts
						(arc
							(start -0.1778 -0.2794)
							(mid -0.249642 -0.249642)
							(end -0.2794 -0.1778)
						)
						(arc
							(start -0.2794 0.1778)
							(mid -0.249642 0.249642)
							(end -0.1778 0.2794)
						)
						(arc
							(start 0.1778 0.2794)
							(mid 0.249642 0.249642)
							(end 0.2794 0.1778)
						)
						(arc
							(start 0.2794 -0.1778)
							(mid 0.249642 -0.249642)
							(end 0.1778 -0.2794)
						)
					)
					(width 0)
					(fill yes)
				)
			)
		)
	)
	(footprint ""
		(layer "F.Cu")
		(at 117.1194 -131.2926 -90)
		(property "Reference" "R425"
			(at 0 0 270)
			(layer "F.SilkS")
			(hide yes)
			(effects
				(font
					(size 1.27 1.27)
				)
			)
		)
		(property "Value" "0R2J-2-GP"
			(at 0.064008 -3.993896 270)
			(unlocked yes)
			(layer "F.Fab")
			(hide yes)
			(effects
				(font
					(size 1.016 1.016)
					(thickness 0.1524)
				)
			)
		)
		(property "Device Type" "R402H16"
			(at 0.064008 -5.517896 270)
			(unlocked yes)
			(layer "F.Fab")
			(hide yes)
			(effects
				(font
					(size 1.016 1.016)
					(thickness 0.1524)
				)
			)
		)
		(duplicate_pad_numbers_are_jumpers no)
		(fp_line
			(start -0.508 -0.9398)
			(end -0.508 0.9398)
			(stroke
				(width 0.1524)
				(type default)
			)
			(layer "F.SilkS")
		)
		(fp_line
			(start 0.508 -0.9398)
			(end -0.508 -0.9398)
			(stroke
				(width 0.1524)
				(type default)
			)
			(layer "F.SilkS")
		)
		(fp_rect
			(start -0.508 0.9398)
			(end 0.508 -0.9398)
			(stroke
				(width 0)
				(type default)
			)
			(fill no)
			(layer "F.CrtYd")
		)
		(fp_rect
			(start -0.508 0.9398)
			(end 0.508 -0.9398)
			(stroke
				(width 0)
				(type default)
			)
			(fill no)
			(layer "F.Fab")
		)
		(pad "1" smd custom
			(at 0 -0.4445 270)
			(size 0.1397 0.1397)
			(layers "F.Cu" "F.Mask" "F.Paste")
			(net "DRIVE_B_15_PWR")
			(options
				(clearance outline)
				(anchor circle)
			)
			(primitives
				(gr_poly
					(pts
						(arc
							(start -0.1778 -0.2794)
							(mid -0.249642 -0.249642)
							(end -0.2794 -0.1778)
						)
						(arc
							(start -0.2794 0.1778)
							(mid -0.249642 0.249642)
							(end -0.1778 0.2794)
						)
						(arc
							(start 0.1778 0.2794)
							(mid 0.249642 0.249642)
							(end 0.2794 0.1778)
						)
						(arc
							(start 0.2794 -0.1778)
							(mid 0.249642 -0.249642)
							(end 0.1778 -0.2794)
						)
					)
					(width 0)
					(fill yes)
				)
			)
		)
		(pad "2" smd custom
			(at 0 0.4445 270)
			(size 0.1397 0.1397)
			(layers "F.Cu" "F.Mask" "F.Paste")
			(net "SW_PWR_R_HDD15")
			(options
				(clearance outline)
				(anchor circle)
			)
			(primitives
				(gr_poly
					(pts
						(arc
							(start -0.1778 -0.2794)
							(mid -0.249642 -0.249642)
							(end -0.2794 -0.1778)
						)
						(arc
							(start -0.2794 0.1778)
							(mid -0.249642 0.249642)
							(end -0.1778 0.2794)
						)
						(arc
							(start 0.1778 0.2794)
							(mid 0.249642 0.249642)
							(end 0.2794 0.1778)
						)
						(arc
							(start 0.2794 -0.1778)
							(mid 0.249642 -0.249642)
							(end 0.1778 -0.2794)
						)
					)
					(width 0)
					(fill yes)
				)
			)
		)
	)
	(footprint ""
		(layer "F.Cu")
		(at 48.387 -253.111 90)
		(property "Reference" "R179"
			(at 0 0 90)
			(layer "F.SilkS")
			(hide yes)
			(effects
				(font
					(size 1.27 1.27)
				)
			)
		)
		(property "Value" "4K7R2J-2-GP"
			(at 0.064008 -3.993896 90)
			(unlocked yes)
			(layer "F.Fab")
			(hide yes)
			(effects
				(font
					(size 1.016 1.016)
					(thickness 0.1524)
				)
			)
		)
		(property "Device Type" "R402H16"
			(at 0.064008 -5.517896 90)
			(unlocked yes)
			(layer "F.Fab")
			(hide yes)
			(effects
				(font
					(size 1.016 1.016)
					(thickness 0.1524)
				)
			)
		)
		(duplicate_pad_numbers_are_jumpers no)
		(fp_line
			(start 0.508 -0.9398)
			(end -0.508 -0.9398)
			(stroke
				(width 0.1524)
				(type default)
			)
			(layer "F.SilkS")
		)
		(fp_line
			(start -0.508 -0.9398)
			(end -0.508 0.9398)
			(stroke
				(width 0.1524)
				(type default)
			)
			(layer "F.SilkS")
		)
		(fp_rect
			(start -0.508 0.9398)
			(end 0.508 -0.9398)
			(stroke
				(width 0)
				(type default)
			)
			(fill no)
			(layer "F.CrtYd")
		)
		(fp_rect
			(start -0.508 0.9398)
			(end 0.508 -0.9398)
			(stroke
				(width 0)
				(type default)
			)
			(fill no)
			(layer "F.Fab")
		)
		(pad "1" smd custom
			(at 0 -0.4445 90)
			(size 0.1397 0.1397)
			(layers "F.Cu" "F.Mask" "F.Paste")
			(net "P12V_B")
			(options
				(clearance outline)
				(anchor circle)
			)
			(primitives
				(gr_poly
					(pts
						(arc
							(start -0.1778 -0.2794)
							(mid -0.249642 -0.249642)
							(end -0.2794 -0.1778)
						)
						(arc
							(start -0.2794 0.1778)
							(mid -0.249642 0.249642)
							(end -0.1778 0.2794)
						)
						(arc
							(start 0.1778 0.2794)
							(mid 0.249642 0.249642)
							(end 0.2794 0.1778)
						)
						(arc
							(start 0.2794 -0.1778)
							(mid 0.249642 -0.249642)
							(end 0.1778 -0.2794)
						)
					)
					(width 0)
					(fill yes)
				)
			)
		)
		(pad "2" smd custom
			(at 0 0.4445 90)
			(size 0.1397 0.1397)
			(layers "F.Cu" "F.Mask" "F.Paste")
			(net "SW_HDD_P1")
			(options
				(clearance outline)
				(anchor circle)
			)
			(primitives
				(gr_poly
					(pts
						(arc
							(start -0.1778 -0.2794)
							(mid -0.249642 -0.249642)
							(end -0.2794 -0.1778)
						)
						(arc
							(start -0.2794 0.1778)
							(mid -0.249642 0.249642)
							(end -0.1778 0.2794)
						)
						(arc
							(start 0.1778 0.2794)
							(mid 0.249642 0.249642)
							(end 0.2794 0.1778)
						)
						(arc
							(start 0.2794 -0.1778)
							(mid 0.249642 -0.249642)
							(end 0.1778 -0.2794)
						)
					)
					(width 0)
					(fill yes)
				)
			)
		)
	)
)
